# T6G (Grand Teton) — schematic netlist excerpt (pin names and nets, part order shuffled) for the footprints in the layout excerpt that follows; sources: Cadence DE-HDL packaged netlist, KiCad conversion of 04192023_DAF0TMB3IC0_F0TG_MB_C_brd_V02_OCP.brd

PR433  Q_RES  0 5% CHIP  pkg 0402LF  page 196 : A = PVDDCR_CPU0_P0_VOS6 ; B = PVDDCR_CPU0_P0
PC636_4  Q_CAP  22UF 4V 20% X6S  pkg C0805  page 223 : A = PVDDIO_P1 ; B = GND
R8168  Q_RES  0 5% CHIP  pkg 0402LF  page 210 : A = PVDDCR_CPU0_P1_OCP_N ; B = PVDDCR_CPU0_P1_OCP_N_R

(kicad_pcb
	(version 20260206)
	(generator "pcbnew")
	(generator_version "10.0")
	(general
		(thickness 1.6)
		(legacy_teardrops no)
	)
	(paper "A4")
	(title_block
		(title "04192023_DAF0TMB3IC0_F0TG_MB_C_brd_V02_OCP.brd")
		(comment 1 "Grand Teton / footprints 7479-7481 of 8354")
	)
	(layers
		(0 "F.Cu" signal "TOP")
		(4 "In1.Cu" signal "GND")
		(6 "In2.Cu" signal "IN1")
		(8 "In3.Cu" signal "GND1")
		(10 "In4.Cu" signal "IN2")
		(12 "In5.Cu" signal "GND2")
		(14 "In6.Cu" signal "IN3")
		(16 "In7.Cu" signal "GND3")
		(18 "In8.Cu" signal "VCC")
		(20 "In9.Cu" signal "VCC1")
		(22 "In10.Cu" signal "GND4")
		(24 "In11.Cu" signal "IN4")
		(26 "In12.Cu" signal "GND5")
		(28 "In13.Cu" signal "IN5")
		(30 "In14.Cu" signal "GND6")
		(32 "In15.Cu" signal "IN6")
		(34 "In16.Cu" signal "GND7")
		(2 "B.Cu" signal "BOTTOM")
		(9 "F.Adhes" user "F.Adhesive")
		(11 "B.Adhes" user "B.Adhesive")
		(13 "F.Paste" user "Package Geometry/Pastemask Top")
		(15 "B.Paste" user "Package Geometry/Pastemask Bottom")
		(5 "F.SilkS" user "Ref Des/Silkscreen Top")
		(7 "B.SilkS" user "Ref Des/Silkscreen Bottom")
		(1 "F.Mask" user "Board Geometry/Soldermask Top")
		(3 "B.Mask" user "Board Geometry/Soldermask Bottom")
		(17 "Dwgs.User" user "User.Drawings")
		(19 "Cmts.User" user "User.Comments")
		(21 "Eco1.User" user "User.Eco1")
		(23 "Eco2.User" user "User.Eco2")
		(25 "Edge.Cuts" user "Board Geometry/Outline")
		(27 "Margin" user)
		(31 "F.CrtYd" user "Package Geometry/Place Bound Top")
		(29 "B.CrtYd" user "Package Geometry/Place Bound Bottom")
		(35 "F.Fab" user "Ref Des/Assembly Top")
		(33 "B.Fab" user "Ref Des/Assembly Bottom")
	)
	(footprint ""
		(layer "B.Cu")
		(at 101.385878 -145.64741)
		(property "Reference" "R8168"
			(at 0 0 0)
			(layer "B.SilkS")
			(hide yes)
			(effects
				(font
					(size 1.27 1.27)
				)
				(justify mirror)
			)
		)
		(property "Value" ""
			(at 0 0 0)
			(layer "B.Fab")
			(effects
				(font
					(size 1.27 1.27)
				)
				(justify mirror)
			)
		)
		(duplicate_pad_numbers_are_jumpers no)
		(fp_line
			(start -0.7874 -0.4064)
			(end -0.7874 0.4064)
			(stroke
				(width 0.1524)
				(type default)
			)
			(layer "B.SilkS")
		)
		(fp_line
			(start -0.7874 0.4064)
			(end 0.7874 0.4064)
			(stroke
				(width 0.1524)
				(type default)
			)
			(layer "B.SilkS")
		)
		(fp_line
			(start 0.7874 -0.4064)
			(end -0.7874 -0.4064)
			(stroke
				(width 0.1524)
				(type default)
			)
			(layer "B.SilkS")
		)
		(fp_line
			(start 0.7874 0.4064)
			(end 0.7874 -0.4064)
			(stroke
				(width 0.1524)
				(type default)
			)
			(layer "B.SilkS")
		)
		(fp_line
			(start -0.67945 -0.3048)
			(end -0.67945 0.3048)
			(stroke
				(width 0.1)
				(type default)
			)
			(layer "B.Fab")
		)
		(fp_line
			(start -0.67945 0.3048)
			(end -0.120396 0.3048)
			(stroke
				(width 0.1)
				(type default)
			)
			(layer "B.Fab")
		)
		(fp_line
			(start -0.12065 -0.3048)
			(end -0.67945 -0.3048)
			(stroke
				(width 0.1)
				(type default)
			)
			(layer "B.Fab")
		)
		(fp_line
			(start -0.12065 -0.2794)
			(end -0.12065 -0.3048)
			(stroke
				(width 0.1)
				(type default)
			)
			(layer "B.Fab")
		)
		(fp_line
			(start -0.120396 0.2794)
			(end 0.12065 0.2794)
			(stroke
				(width 0.1)
				(type default)
			)
			(layer "B.Fab")
		)
		(fp_line
			(start -0.120396 0.3048)
			(end -0.120396 0.2794)
			(stroke
				(width 0.1)
				(type default)
			)
			(layer "B.Fab")
		)
		(fp_line
			(start 0.12065 -0.305054)
			(end 0.12065 -0.2794)
			(stroke
				(width 0.1)
				(type default)
			)
			(layer "B.Fab")
		)
		(fp_line
			(start 0.12065 -0.2794)
			(end -0.12065 -0.2794)
			(stroke
				(width 0.1)
				(type default)
			)
			(layer "B.Fab")
		)
		(fp_line
			(start 0.12065 0.2794)
			(end 0.12065 0.3048)
			(stroke
				(width 0.1)
				(type default)
			)
			(layer "B.Fab")
		)
		(fp_line
			(start 0.12065 0.3048)
			(end 0.67945 0.3048)
			(stroke
				(width 0.1)
				(type default)
			)
			(layer "B.Fab")
		)
		(fp_line
			(start 0.67945 -0.305054)
			(end 0.12065 -0.305054)
			(stroke
				(width 0.1)
				(type default)
			)
			(layer "B.Fab")
		)
		(fp_line
			(start 0.67945 0.3048)
			(end 0.67945 -0.305054)
			(stroke
				(width 0.1)
				(type default)
			)
			(layer "B.Fab")
		)
		(pad "1" smd circle
			(at 0.40005 0 180)
			(size 0 0)
			(layers "B.Cu" "B.Mask" "B.Paste")
			(net "PVDDCR_CPU0_P1_OCP_N")
		)
		(pad "2" smd circle
			(at -0.40005 0 180)
			(size 0 0)
			(layers "B.Cu" "B.Mask" "B.Paste")
			(net "PVDDCR_CPU0_P1_OCP_N_R")
		)
	)
	(footprint ""
		(layer "B.Cu")
		(at 351.389188 -158.474156 90)
		(property "Reference" "PR433"
			(at 0 0 90)
			(layer "B.SilkS")
			(hide yes)
			(effects
				(font
					(size 1.27 1.27)
				)
				(justify mirror)
			)
		)
		(property "Value" ""
			(at 0 0 90)
			(layer "B.Fab")
			(effects
				(font
					(size 1.27 1.27)
				)
				(justify mirror)
			)
		)
		(duplicate_pad_numbers_are_jumpers no)
		(fp_line
			(start 0.7874 -0.4064)
			(end -0.7874 -0.4064)
			(stroke
				(width 0.1524)
				(type default)
			)
			(layer "B.SilkS")
		)
		(fp_line
			(start -0.7874 -0.4064)
			(end -0.7874 0.4064)
			(stroke
				(width 0.1524)
				(type default)
			)
			(layer "B.SilkS")
		)
		(fp_line
			(start 0.7874 0.4064)
			(end 0.7874 -0.4064)
			(stroke
				(width 0.1524)
				(type default)
			)
			(layer "B.SilkS")
		)
		(fp_line
			(start -0.7874 0.4064)
			(end 0.7874 0.4064)
			(stroke
				(width 0.1524)
				(type default)
			)
			(layer "B.SilkS")
		)
		(fp_line
			(start 0.67945 -0.305054)
			(end 0.12065 -0.305054)
			(stroke
				(width 0.1)
				(type default)
			)
			(layer "B.Fab")
		)
		(fp_line
			(start 0.12065 -0.305054)
			(end 0.12065 -0.2794)
			(stroke
				(width 0.1)
				(type default)
			)
			(layer "B.Fab")
		)
		(fp_line
			(start -0.12065 -0.3048)
			(end -0.67945 -0.3048)
			(stroke
				(width 0.1)
				(type default)
			)
			(layer "B.Fab")
		)
		(fp_line
			(start -0.67945 -0.3048)
			(end -0.67945 0.3048)
			(stroke
				(width 0.1)
				(type default)
			)
			(layer "B.Fab")
		)
		(fp_line
			(start 0.12065 -0.2794)
			(end -0.12065 -0.2794)
			(stroke
				(width 0.1)
				(type default)
			)
			(layer "B.Fab")
		)
		(fp_line
			(start -0.12065 -0.2794)
			(end -0.12065 -0.3048)
			(stroke
				(width 0.1)
				(type default)
			)
			(layer "B.Fab")
		)
		(fp_line
			(start 0.12065 0.2794)
			(end 0.12065 0.3048)
			(stroke
				(width 0.1)
				(type default)
			)
			(layer "B.Fab")
		)
		(fp_line
			(start -0.120396 0.2794)
			(end 0.12065 0.2794)
			(stroke
				(width 0.1)
				(type default)
			)
			(layer "B.Fab")
		)
		(fp_line
			(start 0.67945 0.3048)
			(end 0.67945 -0.305054)
			(stroke
				(width 0.1)
				(type default)
			)
			(layer "B.Fab")
		)
		(fp_line
			(start 0.12065 0.3048)
			(end 0.67945 0.3048)
			(stroke
				(width 0.1)
				(type default)
			)
			(layer "B.Fab")
		)
		(fp_line
			(start -0.120396 0.3048)
			(end -0.120396 0.2794)
			(stroke
				(width 0.1)
				(type default)
			)
			(layer "B.Fab")
		)
		(fp_line
			(start -0.67945 0.3048)
			(end -0.120396 0.3048)
			(stroke
				(width 0.1)
				(type default)
			)
			(layer "B.Fab")
		)
		(pad "1" smd circle
			(at 0.40005 0 270)
			(size 0 0)
			(layers "B.Cu" "B.Mask" "B.Paste")
			(net "PVDDCR_CPU0_P0_VOS6")
		)
		(pad "2" smd circle
			(at -0.40005 0 270)
			(size 0 0)
			(layers "B.Cu" "B.Mask" "B.Paste")
			(net "PVDDCR_CPU0_P0")
		)
	)
	(footprint ""
		(layer "B.Cu")
		(at 31.891732 -337.989672 -90)
		(property "Reference" "PC636_4"
			(at 0 0 90)
			(layer "B.SilkS")
			(hide yes)
			(effects
				(font
					(size 1.27 1.27)
				)
				(justify mirror)
			)
		)
		(property "Value" ""
			(at 0 0 90)
			(layer "B.Fab")
			(effects
				(font
					(size 1.27 1.27)
				)
				(justify mirror)
			)
		)
		(duplicate_pad_numbers_are_jumpers no)
		(fp_line
			(start -1.524 0.762)
			(end 1.524 0.762)
			(stroke
				(width 0.1524)
				(type default)
			)
			(layer "B.SilkS")
		)
		(fp_line
			(start 1.524 0.762)
			(end 1.524 -0.762)
			(stroke
				(width 0.1524)
				(type default)
			)
			(layer "B.SilkS")
		)
		(fp_line
			(start -1.524 -0.762)
			(end -1.524 0.762)
			(stroke
				(width 0.1524)
				(type default)
			)
			(layer "B.SilkS")
		)
		(fp_line
			(start 1.524 -0.762)
			(end -1.524 -0.762)
			(stroke
				(width 0.1524)
				(type default)
			)
			(layer "B.SilkS")
		)
		(fp_line
			(start -1.1049 0.724916)
			(end -1.1049 -0.724916)
			(stroke
				(width 0.1)
				(type default)
			)
			(layer "B.Fab")
		)
		(fp_line
			(start 1.1049 0.724916)
			(end -1.1049 0.724916)
			(stroke
				(width 0.1)
				(type default)
			)
			(layer "B.Fab")
		)
		(fp_line
			(start -1.1049 -0.724916)
			(end 1.1049 -0.724916)
			(stroke
				(width 0.1)
				(type default)
			)
			(layer "B.Fab")
		)
		(fp_line
			(start 1.1049 -0.724916)
			(end 1.1049 0.724916)
			(stroke
				(width 0.1)
				(type default)
			)
			(layer "B.Fab")
		)
		(pad "1" smd rect
			(at 0.889 0 270)
			(size 1.016 1.27)
			(layers "B.Cu" "B.Mask" "B.Paste")
			(net "PVDDIO_P1")
		)
		(pad "2" smd rect
			(at -0.889 0 270)
			(size 1.016 1.27)
			(layers "B.Cu" "B.Mask" "B.Paste")
			(net "GND")
		)
	)
)
